# T6G (Grand Teton) — schematic netlist excerpt (pin names and nets, part order shuffled) for the footprints in the layout excerpt that follows; sources: Cadence DE-HDL packaged netlist, KiCad conversion of 04192023_DAF0TMB3IC0_F0TG_MB_C_brd_V02_OCP.brd

R4506  Q_RES  33.2 1% CHIP  pkg 0402LF  page 150 : A = SMB_CPU0_CPU1_SEC_SCL ; B = SMB_CPU0_CPU1_SEC_SCL_R
PC6813  Q_CAPP  470UF 2.5V 20% SPCAP  pkg SMLF  page 365 : A = P0V9_CPU1_RT_2D ; B = GND

(kicad_pcb
	(version 20260206)
	(generator "pcbnew")
	(generator_version "10.0")
	(general
		(thickness 1.6)
		(legacy_teardrops no)
	)
	(paper "A4")
	(title_block
		(title "04192023_DAF0TMB3IC0_F0TG_MB_C_brd_V02_OCP.brd")
		(comment 1 "Grand Teton / footprints 7801-7802 of 8354")
	)
	(layers
		(0 "F.Cu" signal "TOP")
		(4 "In1.Cu" signal "GND")
		(6 "In2.Cu" signal "IN1")
		(8 "In3.Cu" signal "GND1")
		(10 "In4.Cu" signal "IN2")
		(12 "In5.Cu" signal "GND2")
		(14 "In6.Cu" signal "IN3")
		(16 "In7.Cu" signal "GND3")
		(18 "In8.Cu" signal "VCC")
		(20 "In9.Cu" signal "VCC1")
		(22 "In10.Cu" signal "GND4")
		(24 "In11.Cu" signal "IN4")
		(26 "In12.Cu" signal "GND5")
		(28 "In13.Cu" signal "IN5")
		(30 "In14.Cu" signal "GND6")
		(32 "In15.Cu" signal "IN6")
		(34 "In16.Cu" signal "GND7")
		(2 "B.Cu" signal "BOTTOM")
		(9 "F.Adhes" user "F.Adhesive")
		(11 "B.Adhes" user "B.Adhesive")
		(13 "F.Paste" user "Package Geometry/Pastemask Top")
		(15 "B.Paste" user "Package Geometry/Pastemask Bottom")
		(5 "F.SilkS" user "Ref Des/Silkscreen Top")
		(7 "B.SilkS" user "Ref Des/Silkscreen Bottom")
		(1 "F.Mask" user "Board Geometry/Soldermask Top")
		(3 "B.Mask" user "Board Geometry/Soldermask Bottom")
		(17 "Dwgs.User" user "User.Drawings")
		(19 "Cmts.User" user "User.Comments")
		(21 "Eco1.User" user "User.Eco1")
		(23 "Eco2.User" user "User.Eco2")
		(25 "Edge.Cuts" user "Board Geometry/Outline")
		(27 "Margin" user)
		(31 "F.CrtYd" user "Package Geometry/Place Bound Top")
		(29 "B.CrtYd" user "Package Geometry/Place Bound Bottom")
		(35 "F.Fab" user "Ref Des/Assembly Top")
		(33 "B.Fab" user "Ref Des/Assembly Bottom")
	)
	(footprint ""
		(layer "B.Cu")
		(at 177.443638 -13.762228 90)
		(property "Reference" "R4506"
			(at 0 0 90)
			(layer "B.SilkS")
			(hide yes)
			(effects
				(font
					(size 1.27 1.27)
				)
				(justify mirror)
			)
		)
		(property "Value" ""
			(at 0 0 90)
			(layer "B.Fab")
			(effects
				(font
					(size 1.27 1.27)
				)
				(justify mirror)
			)
		)
		(duplicate_pad_numbers_are_jumpers no)
		(fp_line
			(start 0.7874 -0.4064)
			(end -0.7874 -0.4064)
			(stroke
				(width 0.1524)
				(type default)
			)
			(layer "B.SilkS")
		)
		(fp_line
			(start -0.7874 -0.4064)
			(end -0.7874 0.4064)
			(stroke
				(width 0.1524)
				(type default)
			)
			(layer "B.SilkS")
		)
		(fp_line
			(start 0.7874 0.4064)
			(end 0.7874 -0.4064)
			(stroke
				(width 0.1524)
				(type default)
			)
			(layer "B.SilkS")
		)
		(fp_line
			(start -0.7874 0.4064)
			(end 0.7874 0.4064)
			(stroke
				(width 0.1524)
				(type default)
			)
			(layer "B.SilkS")
		)
		(fp_line
			(start 0.67945 -0.305054)
			(end 0.12065 -0.305054)
			(stroke
				(width 0.1)
				(type default)
			)
			(layer "B.Fab")
		)
		(fp_line
			(start 0.12065 -0.305054)
			(end 0.12065 -0.2794)
			(stroke
				(width 0.1)
				(type default)
			)
			(layer "B.Fab")
		)
		(fp_line
			(start -0.12065 -0.3048)
			(end -0.67945 -0.3048)
			(stroke
				(width 0.1)
				(type default)
			)
			(layer "B.Fab")
		)
		(fp_line
			(start -0.67945 -0.3048)
			(end -0.67945 0.3048)
			(stroke
				(width 0.1)
				(type default)
			)
			(layer "B.Fab")
		)
		(fp_line
			(start 0.12065 -0.2794)
			(end -0.12065 -0.2794)
			(stroke
				(width 0.1)
				(type default)
			)
			(layer "B.Fab")
		)
		(fp_line
			(start -0.12065 -0.2794)
			(end -0.12065 -0.3048)
			(stroke
				(width 0.1)
				(type default)
			)
			(layer "B.Fab")
		)
		(fp_line
			(start 0.12065 0.2794)
			(end 0.12065 0.3048)
			(stroke
				(width 0.1)
				(type default)
			)
			(layer "B.Fab")
		)
		(fp_line
			(start -0.120396 0.2794)
			(end 0.12065 0.2794)
			(stroke
				(width 0.1)
				(type default)
			)
			(layer "B.Fab")
		)
		(fp_line
			(start 0.67945 0.3048)
			(end 0.67945 -0.305054)
			(stroke
				(width 0.1)
				(type default)
			)
			(layer "B.Fab")
		)
		(fp_line
			(start 0.12065 0.3048)
			(end 0.67945 0.3048)
			(stroke
				(width 0.1)
				(type default)
			)
			(layer "B.Fab")
		)
		(fp_line
			(start -0.120396 0.3048)
			(end -0.120396 0.2794)
			(stroke
				(width 0.1)
				(type default)
			)
			(layer "B.Fab")
		)
		(fp_line
			(start -0.67945 0.3048)
			(end -0.120396 0.3048)
			(stroke
				(width 0.1)
				(type default)
			)
			(layer "B.Fab")
		)
		(pad "1" smd circle
			(at 0.40005 0 270)
			(size 0 0)
			(layers "B.Cu" "B.Mask" "B.Paste")
			(net "SMB_CPU0_CPU1_SEC_SCL")
		)
		(pad "2" smd circle
			(at -0.40005 0 270)
			(size 0 0)
			(layers "B.Cu" "B.Mask" "B.Paste")
			(net "SMB_CPU0_CPU1_SEC_SCL_R")
		)
	)
	(footprint ""
		(layer "B.Cu")
		(at 14.340332 -383.53873 -90)
		(property "Reference" "PC6813"
			(at -3.17627 3.191002 270)
			(unlocked yes)
			(layer "B.SilkS")
			(effects
				(font
					(size 0.7874 0.5842)
					(thickness 0.1524)
				)
				(justify left mirror)
			)
		)
		(property "Value" ""
			(at 0 0 90)
			(layer "B.Fab")
			(effects
				(font
					(size 1.27 1.27)
				)
				(justify mirror)
			)
		)
		(duplicate_pad_numbers_are_jumpers no)
		(fp_line
			(start 4.83108 2.150364)
			(end 4.447794 2.149348)
			(stroke
				(width 0.1524)
				(type default)
			)
			(layer "B.SilkS")
		)
		(fp_line
			(start -4.53898 2.15011)
			(end 4.53898 2.15011)
			(stroke
				(width 0.1524)
				(type default)
			)
			(layer "B.SilkS")
		)
		(fp_line
			(start 4.53898 2.15011)
			(end 4.53898 -2.15011)
			(stroke
				(width 0.1524)
				(type default)
			)
			(layer "B.SilkS")
		)
		(fp_line
			(start -4.53898 -2.15011)
			(end -4.53898 2.15011)
			(stroke
				(width 0.1524)
				(type default)
			)
			(layer "B.SilkS")
		)
		(fp_line
			(start 4.53898 -2.15011)
			(end -4.53898 -2.15011)
			(stroke
				(width 0.1524)
				(type default)
			)
			(layer "B.SilkS")
		)
		(fp_line
			(start 4.53898 -2.150618)
			(end 4.539742 2.152142)
			(stroke
				(width 0.1524)
				(type default)
			)
			(layer "B.SilkS")
		)
		(fp_line
			(start 4.69138 -2.150618)
			(end 4.692396 2.161032)
			(stroke
				(width 0.1524)
				(type default)
			)
			(layer "B.SilkS")
		)
		(fp_line
			(start 4.84378 -2.150618)
			(end 4.842256 2.163064)
			(stroke
				(width 0.1524)
				(type default)
			)
			(layer "B.SilkS")
		)
		(fp_line
			(start 4.84378 -2.150618)
			(end 4.53898 -2.150618)
			(stroke
				(width 0.1524)
				(type default)
			)
			(layer "B.SilkS")
		)
		(fp_line
			(start -3.64998 2.15011)
			(end 3.64998 2.15011)
			(stroke
				(width 0.1)
				(type default)
			)
			(layer "B.Fab")
		)
		(fp_line
			(start 3.64998 2.15011)
			(end 3.64998 -2.15011)
			(stroke
				(width 0.1)
				(type default)
			)
			(layer "B.Fab")
		)
		(fp_line
			(start -3.64998 -2.15011)
			(end -3.64998 2.15011)
			(stroke
				(width 0.1)
				(type default)
			)
			(layer "B.Fab")
		)
		(fp_line
			(start 3.64998 -2.15011)
			(end -3.64998 -2.15011)
			(stroke
				(width 0.1)
				(type default)
			)
			(layer "B.Fab")
		)
		(fp_text user "-"
			(at -4.535678 -1.371346 270)
			(unlocked yes)
			(layer "B.SilkS")
			(effects
				(font
					(size 1.905 1.4224)
					(thickness 0.1524)
				)
				(justify left mirror)
			)
		)
		(fp_text user "+"
			(at 6.222492 -1.50114 270)
			(unlocked yes)
			(layer "B.SilkS")
			(effects
				(font
					(size 1.905 1.4224)
					(thickness 0.1524)
				)
				(justify left mirror)
			)
		)
		(fp_text user "-"
			(at -4.313174 -0.094488 270)
			(unlocked yes)
			(layer "B.Fab")
			(effects
				(font
					(size 1.905 1.4224)
					(thickness 0.1524)
				)
				(justify left mirror)
			)
		)
		(fp_text user "+"
			(at 6.214872 -0.337058 270)
			(unlocked yes)
			(layer "B.Fab")
			(effects
				(font
					(size 1.905 1.4224)
					(thickness 0.1524)
				)
				(justify left mirror)
			)
		)
		(pad "1" smd rect
			(at 3.199892 0 90)
			(size 2.413 2.8194)
			(layers "B.Cu" "B.Mask" "B.Paste")
			(net "P0V9_CPU1_RT_2D")
		)
		(pad "2" smd rect
			(at -3.199892 0 90)
			(size 2.413 2.8194)
			(layers "B.Cu" "B.Mask" "B.Paste")
			(net "GND")
		)
	)
)
